FILE_TYPE = MACRO_DRAWING;
SET COLOR_WIRE YELLOW;
SET COLOR_PROP ORANGE;
SET COLOR_DOT WHITE;
SET COLOR_ARC YELLOW;
SET COLOR_BODY GREEN;
SET COLOR_NOTE PURPLE;
SET PROP_DISPLAY VALUE;
SET PAGE_NUMBER P432;
FORCEADD OFFPAGE..3
R 2
(-7475 5550);
FORCEPROP 2 LAST $XR1 186 
J 0
(-7905 5550);
DISPLAY 0.638298 (-7905 5550);
PAINT MONO (-7905 5550);
FORCEPROP 2 LAST $XR0 185 
J 0
(-7785 5550);
DISPLAY 0.638298 (-7785 5550);
PAINT MONO (-7785 5550);
FORCEPROP 2 LAST CDS_LIB standard
J 0
(-7475 5550);
DISPLAY INVISIBLE (-7475 5550);
FORCEPROP 1 LAST OFFPAGE TRUE
J 2
(-7800 5425);
DISPLAY 0.872340 (-7800 5425);
PAINT GREEN (-7800 5425);
DISPLAY INVISIBLE (-7800 5425);
FORCEPROP 1 LAST COMMENT_BODY TRUE
J 2
(-7425 5450);
DISPLAY 0.872340 (-7425 5450);
PAINT GREEN (-7425 5450);
DISPLAY INVISIBLE (-7425 5450);
FORCEPROP 2 LAST PATH I1
J 0
(-7425 5625);
DISPLAY 0.680851 (-7425 5625);
DISPLAY INVISIBLE (-7425 5625);
FORCEADD Q_RES..2
(-4175 5400);
FORCEPROP 1 LAST LOCATION R1127
J 0
(-4130 5525);
DISPLAY 0.978723 (-4130 5525);
FORCEPROP 0 LAST $SEC 1
J 0
(-4125 5575);
DISPLAY 0.680851 (-4125 5575);
PAINT MONO (-4125 5575);
DISPLAY INVISIBLE (-4125 5575);
FORCEPROP 0 LAST CDS_SEC 1
J 0
(-4125 5575);
DISPLAY 0.680851 (-4125 5575);
DISPLAY INVISIBLE (-4125 5575);
FORCEPROP 1 LASTPIN (-4175 5500) $PN 1
J 0
(-4170 5462);
DISPLAY 0.787234 (-4170 5462);
PAINT MONO (-4170 5462);
FORCEPROP 1 LASTPIN (-4175 5300) $PN 2
J 0
(-4170 5310);
DISPLAY 0.787234 (-4170 5310);
PAINT MONO (-4170 5310);
FORCEPROP 1 LAST PACK_TYPE 0201LF
J 0
(-4135 5225);
DISPLAY 0.978723 (-4135 5225);
FORCEPROP 1 LAST MATERIAL CHIP
J 0
(-4135 5325);
DISPLAY 0.978723 (-4135 5325);
FORCEPROP 1 LAST WATTAGE 1/20W
J 0
(-4135 5375);
DISPLAY 0.978723 (-4135 5375);
FORCEPROP 1 LAST TOLERANCE 1%
J 0
(-4130 5425);
DISPLAY 0.978723 (-4130 5425);
FORCEPROP 1 LAST VALUE 1K
J 0
(-4130 5475);
DISPLAY 0.978723 (-4130 5475);
FORCEPROP 2 LAST CDS_LIB pure_quanta
J 0
(-4175 5400);
DISPLAY INVISIBLE (-4175 5400);
FORCEPROP 1 LAST PATH I18
J 0
(-4125 5575);
DISPLAY 0.978723 (-4125 5575);
PAINT WHITE (-4125 5575);
DISPLAY INVISIBLE (-4125 5575);
FORCEPROP 1 LAST PART_NUMBER CS21001FE07
J 0
(-4135 5275);
DISPLAY 0.978723 (-4135 5275);
DISPLAY INVISIBLE (-4135 5275);
FORCEADD UNIVERSAL_GND..1
(-4325 5325);
FORCEPROP 3 LASTPIN (-4325 5375) SIG_NAME GND\g
J 0
(-4315 5385);
DISPLAY 0.659574 (-4315 5385);
PAINT MONO (-4315 5385);
DISPLAY INVISIBLE (-4315 5385);
FORCEPROP 2 LAST CDS_LIB pure_quanta_power
J 0
(-4325 5325);
DISPLAY INVISIBLE (-4325 5325);
FORCEPROP 1 LAST HDL_POWER GND
J 1
(-4300 5250);
DISPLAY 0.872340 (-4300 5250);
PAINT GREEN (-4300 5250);
DISPLAY INVISIBLE (-4300 5250);
FORCEPROP 1 LAST PATH I19
J 0
(-4250 5325);
DISPLAY 0.872340 (-4250 5325);
PAINT AQUA (-4250 5325);
DISPLAY INVISIBLE (-4250 5325);
FORCEADD OFFPAGE..1
(-7500 5600);
FORCEPROP 2 LAST $XR1 186 
J 0
(-7872 5600);
DISPLAY 0.638298 (-7872 5600);
PAINT MONO (-7872 5600);
FORCEPROP 2 LAST $XR0 185 
J 0
(-7752 5600);
DISPLAY 0.638298 (-7752 5600);
PAINT MONO (-7752 5600);
FORCEPROP 2 LAST CDS_LIB standard
J 0
(-7500 5600);
DISPLAY INVISIBLE (-7500 5600);
FORCEPROP 1 LAST OFFPAGE TRUE
J 0
(-7175 5475);
DISPLAY 0.872340 (-7175 5475);
DISPLAY INVISIBLE (-7175 5475);
FORCEPROP 1 LAST COMMENT_BODY TRUE
J 0
(-7375 5500);
DISPLAY 0.872340 (-7375 5500);
PAINT GREEN (-7375 5500);
DISPLAY INVISIBLE (-7375 5500);
FORCEPROP 2 LAST PATH I2
J 0
(-7450 5675);
DISPLAY 0.680851 (-7450 5675);
DISPLAY INVISIBLE (-7450 5675);
FORCEADD UNIVERSAL_GND..1
(-4175 4975);
FORCEPROP 3 LASTPIN (-4175 5025) SIG_NAME GND\g
J 0
(-4165 5035);
DISPLAY 0.659574 (-4165 5035);
PAINT MONO (-4165 5035);
DISPLAY INVISIBLE (-4165 5035);
FORCEPROP 2 LAST CDS_LIB pure_quanta_power
J 0
(-4175 4975);
DISPLAY INVISIBLE (-4175 4975);
FORCEPROP 1 LAST HDL_POWER GND
J 1
(-4150 4900);
DISPLAY 0.872340 (-4150 4900);
PAINT GREEN (-4150 4900);
DISPLAY INVISIBLE (-4150 4900);
FORCEPROP 1 LAST PATH I20
J 0
(-4100 4975);
DISPLAY 0.872340 (-4100 4975);
PAINT AQUA (-4100 4975);
DISPLAY INVISIBLE (-4100 4975);
FORCEADD UNIVERSAL_GND..1
R 7
(-5275 5650);
FORCEPROP 3 LASTPIN (-5225 5650) SIG_NAME GND\g
J 0
(-5215 5660);
DISPLAY 0.659574 (-5215 5660);
PAINT MONO (-5215 5660);
DISPLAY INVISIBLE (-5215 5660);
FORCEPROP 2 LAST CDS_LIB pure_quanta_power
J 0
(-5275 5650);
DISPLAY INVISIBLE (-5275 5650);
FORCEPROP 1 LAST HDL_POWER GND
R 1
J 1
(-5350 5675);
DISPLAY 0.872340 (-5350 5675);
PAINT GREEN (-5350 5675);
DISPLAY INVISIBLE (-5350 5675);
FORCEPROP 1 LAST PATH I21
R 1
J 0
(-5275 5725);
DISPLAY 0.872340 (-5275 5725);
PAINT AQUA (-5275 5725);
DISPLAY INVISIBLE (-5275 5725);
FORCEADD P1V0..1
(-5275 6475);
FORCEPROP 3 LASTPIN (-5275 6425) SIG_NAME P1V8_CPU0_RT_1D\g
J 0
(-5265 6435);
DISPLAY 0.659574 (-5265 6435);
PAINT MONO (-5265 6435);
DISPLAY INVISIBLE (-5265 6435);
FORCEPROP 1 LAST HDL_POWER P1V8_CPU0_RT_1D
J 1
(-5275 6525);
DISPLAY 0.489362 (-5275 6525);
PAINT SKYBLUE (-5275 6525);
FORCEPROP 2 LAST CDS_LIB pure_quanta_power
J 0
(-5275 6475);
DISPLAY INVISIBLE (-5275 6475);
FORCEPROP 1 LAST PATH I22
J 0
(-5225 6500);
DISPLAY 0.872340 (-5225 6500);
PAINT AQUA (-5225 6500);
DISPLAY INVISIBLE (-5225 6500);
FORCEADD Q_CAP..1
(-5575 6125);
FORCEPROP 1 LAST LOCATION C1057
J 0
(-5525 6225);
DISPLAY 0.787234 (-5525 6225);
PAINT SKYBLUE (-5525 6225);
FORCEPROP 0 LAST $SEC 1
J 0
(-5525 6275);
DISPLAY 0.680851 (-5525 6275);
PAINT MONO (-5525 6275);
DISPLAY INVISIBLE (-5525 6275);
FORCEPROP 0 LAST CDS_SEC 1
J 0
(-5525 6275);
DISPLAY 0.680851 (-5525 6275);
DISPLAY INVISIBLE (-5525 6275);
FORCEPROP 1 LASTPIN (-5575 6225) $PN 1
J 0
(-5565 6205);
DISPLAY 0.787234 (-5565 6205);
PAINT MONO (-5565 6205);
FORCEPROP 1 LASTPIN (-5575 6025) $PN 2
J 0
(-5565 6005);
DISPLAY 0.787234 (-5565 6005);
PAINT MONO (-5565 6005);
FORCEPROP 1 LAST VOLTAGE 10V
J 0
(-5525 6125);
DISPLAY 0.510638 (-5525 6125);
FORCEPROP 1 LAST TOLERANCE 10%
J 0
(-5525 6075);
DISPLAY 0.510638 (-5525 6075);
FORCEPROP 1 LAST MATERIAL X7S
J 0
(-5525 6025);
DISPLAY 0.510638 (-5525 6025);
FORCEPROP 1 LAST PACK_TYPE C0201
J 0
(-5525 5975);
DISPLAY 0.510638 (-5525 5975);
FORCEPROP 1 LAST VALUE 0.1UF
J 0
(-5525 6175);
DISPLAY 0.510638 (-5525 6175);
FORCEPROP 2 LAST CDS_LIB pure_quanta
J 0
(-5575 6125);
DISPLAY INVISIBLE (-5575 6125);
FORCEPROP 1 LAST PATH I23
J 0
(-5525 6275);
DISPLAY 0.978723 (-5525 6275);
PAINT WHITE (-5525 6275);
DISPLAY INVISIBLE (-5525 6275);
FORCEPROP 1 LAST PART_NUMBER CH4102K6E00
J 0
(-5525 5975);
DISPLAY 0.978723 (-5525 5975);
DISPLAY INVISIBLE (-5525 5975);
FORCEADD UNIVERSAL_GND..1
(-5575 5850);
FORCEPROP 3 LASTPIN (-5575 5900) SIG_NAME GND\g
J 0
(-5565 5910);
DISPLAY 0.659574 (-5565 5910);
PAINT MONO (-5565 5910);
DISPLAY INVISIBLE (-5565 5910);
FORCEPROP 2 LAST CDS_LIB pure_quanta_power
J 0
(-5575 5850);
DISPLAY INVISIBLE (-5575 5850);
FORCEPROP 1 LAST HDL_POWER GND
J 1
(-5550 5775);
DISPLAY 0.872340 (-5550 5775);
PAINT GREEN (-5550 5775);
DISPLAY INVISIBLE (-5550 5775);
FORCEPROP 1 LAST PATH I24
J 0
(-5500 5850);
DISPLAY 0.872340 (-5500 5850);
PAINT AQUA (-5500 5850);
DISPLAY INVISIBLE (-5500 5850);
FORCEADD Q_RES..1
(-6275 5600);
FORCEPROP 1 LAST LOCATION R687
J 0
(-6525 5600);
DISPLAY 0.978723 (-6525 5600);
FORCEPROP 0 LAST $SEC 1
J 0
(-6325 5775);
DISPLAY 0.680851 (-6325 5775);
PAINT MONO (-6325 5775);
DISPLAY INVISIBLE (-6325 5775);
FORCEPROP 0 LAST CDS_SEC 1
J 0
(-6325 5775);
DISPLAY 0.680851 (-6325 5775);
DISPLAY INVISIBLE (-6325 5775);
FORCEPROP 1 LASTPIN (-6375 5600) $PN 1
J 0
(-6363 5612);
DISPLAY 0.787234 (-6363 5612);
PAINT MONO (-6363 5612);
FORCEPROP 1 LASTPIN (-6175 5600) $PN 2
J 0
(-6213 5612);
DISPLAY 0.787234 (-6213 5612);
PAINT MONO (-6213 5612);
FORCEPROP 1 LAST MATERIAL CHIP
J 0
(-6450 5675);
DISPLAY 0.787234 (-6450 5675);
FORCEPROP 1 LAST WATTAGE 1/20W
J 2
(-6475 5675);
DISPLAY 0.787234 (-6475 5675);
FORCEPROP 1 LAST PACK_TYPE 0201LF
J 0
(-6250 5675);
DISPLAY 0.787234 (-6250 5675);
FORCEPROP 1 LAST VALUE 33.2
J 2
(-6475 5725);
DISPLAY 0.787234 (-6475 5725);
FORCEPROP 1 LAST TOLERANCE 1%
J 0
(-6450 5725);
DISPLAY 0.787234 (-6450 5725);
FORCEPROP 2 LAST CDS_LIB pure_quanta
J 0
(-6275 5600);
DISPLAY INVISIBLE (-6275 5600);
FORCEPROP 1 LAST PATH I3
J 0
(-6325 5750);
DISPLAY 0.978723 (-6325 5750);
PAINT WHITE (-6325 5750);
DISPLAY INVISIBLE (-6325 5750);
FORCEPROP 1 LAST PART_NUMBER CS03321FE09
J 0
(-6325 5725);
DISPLAY 0.808511 (-6325 5725);
DISPLAY INVISIBLE (-6325 5725);
FORCEADD Q_RES..1
(-6275 5550);
FORCEPROP 1 LAST LOCATION R688
J 0
(-6525 5550);
DISPLAY 0.978723 (-6525 5550);
FORCEPROP 0 LAST $SEC 1
J 0
(-6525 5600);
DISPLAY 0.680851 (-6525 5600);
PAINT MONO (-6525 5600);
DISPLAY INVISIBLE (-6525 5600);
FORCEPROP 0 LAST CDS_SEC 1
J 0
(-6525 5600);
DISPLAY 0.680851 (-6525 5600);
DISPLAY INVISIBLE (-6525 5600);
FORCEPROP 1 LASTPIN (-6375 5550) $PN 1
J 0
(-6363 5562);
DISPLAY 0.787234 (-6363 5562);
PAINT MONO (-6363 5562);
FORCEPROP 1 LASTPIN (-6175 5550) $PN 2
J 0
(-6213 5562);
DISPLAY 0.787234 (-6213 5562);
PAINT MONO (-6213 5562);
FORCEPROP 1 LAST MATERIAL CHIP
J 0
(-6450 5625);
DISPLAY 0.787234 (-6450 5625);
DISPLAY INVISIBLE (-6450 5625);
FORCEPROP 2 LAST CDS_LIB pure_quanta
J 0
(-6275 5550);
DISPLAY INVISIBLE (-6275 5550);
FORCEPROP 1 LAST WATTAGE 1/20W
J 2
(-6475 5625);
DISPLAY 0.787234 (-6475 5625);
DISPLAY INVISIBLE (-6475 5625);
FORCEPROP 1 LAST PACK_TYPE 0201LF
J 0
(-6250 5625);
DISPLAY 0.787234 (-6250 5625);
DISPLAY INVISIBLE (-6250 5625);
FORCEPROP 1 LAST VALUE 33.2
J 2
(-6475 5675);
DISPLAY 0.787234 (-6475 5675);
DISPLAY INVISIBLE (-6475 5675);
FORCEPROP 1 LAST TOLERANCE 1%
J 0
(-6450 5675);
DISPLAY 0.787234 (-6450 5675);
DISPLAY INVISIBLE (-6450 5675);
FORCEPROP 1 LAST PATH I4
J 0
(-6325 5700);
DISPLAY 0.978723 (-6325 5700);
PAINT WHITE (-6325 5700);
DISPLAY INVISIBLE (-6325 5700);
FORCEPROP 1 LAST PART_NUMBER CS03321FE09
J 0
(-6325 5675);
DISPLAY 0.808511 (-6325 5675);
DISPLAY INVISIBLE (-6325 5675);
FORCEADD M24M02DRMN6TP..1
(-4850 5625);
FORCEPROP 1 LAST LOCATION U17
J 0
(-5044 5965);
DISPLAY 0.723404 (-5044 5965);
PAINT GREEN (-5044 5965);
FORCEPROP 0 LAST $SEC 1
J 0
(-5025 6100);
DISPLAY 0.680851 (-5025 6100);
PAINT MONO (-5025 6100);
DISPLAY INVISIBLE (-5025 6100);
FORCEPROP 0 LAST CDS_SEC 1
J 0
(-5025 6100);
DISPLAY 0.680851 (-5025 6100);
DISPLAY INVISIBLE (-5025 6100);
FORCEPROP 0 LASTPIN (-4525 5700) $PN 1
J 0
(-4515 5710);
DISPLAY 0.680851 (-4515 5710);
PAINT MONO (-4515 5710);
FORCEPROP 0 LASTPIN (-4525 5650) $PN 2
J 0
(-4515 5660);
DISPLAY 0.680851 (-4515 5660);
PAINT MONO (-4515 5660);
FORCEPROP 0 LASTPIN (-4525 5600) $PN 3
J 0
(-4515 5610);
DISPLAY 0.680851 (-4515 5610);
PAINT MONO (-4515 5610);
FORCEPROP 0 LASTPIN (-5175 5600) $PN 6
J 2
(-5185 5610);
DISPLAY 0.680851 (-5185 5610);
PAINT MONO (-5185 5610);
FORCEPROP 0 LASTPIN (-5175 5550) $PN 5
J 2
(-5185 5560);
DISPLAY 0.680851 (-5185 5560);
PAINT MONO (-5185 5560);
FORCEPROP 0 LASTPIN (-5175 5700) $PN 8
J 2
(-5185 5710);
DISPLAY 0.680851 (-5185 5710);
PAINT MONO (-5185 5710);
FORCEPROP 0 LASTPIN (-4525 5550) $PN 4
J 0
(-4515 5560);
DISPLAY 0.680851 (-4515 5560);
PAINT MONO (-4515 5560);
FORCEPROP 0 LASTPIN (-5175 5650) $PN 7
J 2
(-5185 5660);
DISPLAY 0.680851 (-5185 5660);
PAINT MONO (-5185 5660);
FORCEPROP 2 LAST PART_TYPE SMLF
J 0
(-5025 6050);
DISPLAY 0.680851 (-5025 6050);
FORCEPROP 1 LAST MATERIAL IC
J 0
(-5044 5757);
DISPLAY 0.723404 (-5044 5757);
PAINT GREEN (-5044 5757);
FORCEPROP 2 LAST VALUE M24M02-DRMN6TP
J 0
(-5025 6000);
DISPLAY 0.680851 (-5025 6000);
FORCEPROP 2 LAST CDS_LIB pure_quanta
J 0
(-4850 5625);
DISPLAY INVISIBLE (-4850 5625);
FORCEPROP 1 LAST CDS_LMAN_SYM_OUTLINE -175,125,175,-125
J 0
(-4850 5625);
DISPLAY 0.468085 (-4850 5625);
PAINT GREEN (-4850 5625);
DISPLAY INVISIBLE (-4850 5625);
FORCEPROP 1 LAST NEEDS_NO_SIZE TRUE
J 0
(-4675 5557);
DISPLAY 0.723404 (-4675 5557);
PAINT GREEN (-4675 5557);
DISPLAY INVISIBLE (-4675 5557);
FORCEPROP 1 LAST PATH I5
J 0
(-4675 5500);
DISPLAY 0.723404 (-4675 5500);
PAINT GREEN (-4675 5500);
DISPLAY INVISIBLE (-4675 5500);
FORCEPROP 1 LAST PART_NUMBER AKE33Z00600
J 0
(-5044 5851);
DISPLAY 0.723404 (-5044 5851);
PAINT GREEN (-5044 5851);
DISPLAY INVISIBLE (-5044 5851);
FORCEADD QUANTA_TITLE_BLOCK_C..1
(0 0);
FORCEPROP 0 LAST CDS_CON_LAST_MODIFIED Thu Sep 14 16:13:00 2023
J 0
(-1885 15);
DISPLAY INVISIBLE (-1885 15);
FORCEPROP 1 LAST CUSTOM_TXT_CDS <CON_LAST_MODIFIED>
J 0
(-1885 15);
DISPLAY 0.978723 (-1885 15);
FORCEPROP 2 LAST CUSTOM_TXT_CDS <XR_PAGE_TITLE>
J 0
(-7890 5250);
DISPLAY 0.638298 (-7890 5250);
PAINT PINK (-7890 5250);
DISPLAY INVISIBLE (-7890 5250);
FORCEPROP 1 LAST CUSTOM_TXT_CDS <NAME_2>
J 0
(-3175 50);
FORCEPROP 1 LAST CUSTOM_TXT_CDS <NAME_1>
J 0
(-3175 175);
FORCEPROP 1 LAST CUSTOM_TXT_CDS <Q_NUMBER>
J 0
(-1403 103);
DISPLAY 1.212766 (-1403 103);
FORCEPROP 1 LAST CUSTOM_TXT_CDS <Q_PROJ>
J 0
(-2382 102);
DISPLAY 1.212766 (-2382 102);
FORCEPROP 1 LAST CUSTOM_TXT_CDS <Q_REV>
J 0
(-184 103);
DISPLAY 1.212766 (-184 103);
FORCEPROP 1 LAST CUSTOM_TXT_CDS <CON_PAGE_NUM> OF <CON_TOTAL_PAGES>
J 0
(-446 18);
DISPLAY 0.978723 (-446 18);
FORCEPROP 1 LAST Q_TITLE RETIMER_CPU0_P3(7)
J 0
(-9366 26);
DISPLAY 2.446809 (-9366 26);
PAINT GREEN (-9366 26);
FORCEPROP 2 LAST PAGE_BORDER TRUE
J 0
(-7890 5250);
DISPLAY 0.638298 (-7890 5250);
PAINT PINK (-7890 5250);
DISPLAY INVISIBLE (-7890 5250);
FORCEPROP 1 LAST CDS_LMAN_SYM_OUTLINE -9475,6775,100,-125
J 0
(0 0);
DISPLAY 0.468085 (0 0);
PAINT GREEN (0 0);
DISPLAY INVISIBLE (0 0);
FORCEPROP 2 LAST CDS_LIB pure_quanta
J 0
(0 0);
DISPLAY INVISIBLE (0 0);
FORCEPROP 2 LAST CDS_XR_PAGE_TITLE CR-312 : @T6G_MB_LIB.T6G(SCH_1):PAGE312
J 0
(-7890 5250);
DISPLAY 0.638298 (-7890 5250);
PAINT PINK (-7890 5250);
DISPLAY INVISIBLE (-7890 5250);
FORCEPROP 1 LAST Q_DEPT BU9
J 1
(-3763 49);
DISPLAY 1.957447 (-3763 49);
PAINT GREEN (-3763 49);
DISPLAY INVISIBLE (-3763 49);
FORCEPROP 1 LAST COMMENT_BODY TRUE
J 0
(12 -13);
DISPLAY 0.978723 (12 -13);
PAINT GREEN (12 -13);
DISPLAY INVISIBLE (12 -13);
WIRE 16 -1 (-4525 5550)(-4325 5550);
WIRE 16 -1 (-4325 5550)(-4325 5375);
WIRE 16 -1 (-4175 5300)(-4175 5025);
WIRE 16 -1 (-5175 5650)(-5225 5650);
WIRE 16 -1 (-5575 6025)(-5575 5900);
WIRE 16 -1 (-6375 5550)(-7425 5550);
FORCEPROP 2 LAST SIG_NAME SMB_RT_CPU0_P3_ROM_R_SDA
J 0
(-7335 5560);
DISPLAY 0.680851 (-7335 5560);
WIRE 16 -1 (-5175 5550)(-6175 5550);
FORCEPROP 2 LAST SIG_NAME SMB_RT_CPU0_P3_ROM_SDA
J 0
(-6060 5560);
DISPLAY 0.680851 (-6060 5560);
FORCEPROP 2 LASTPROP $XRERR UNIQUE?
J 0
(-6300 5560);
DISPLAY 0.638298 (-6300 5560);
PAINT MONO (-6300 5560);
DISPLAY INVISIBLE (-6300 5560);
WIRE 16 -1 (-6375 5600)(-7450 5600);
FORCEPROP 2 LAST SIG_NAME SMB_RT_CPU0_P3_ROM_R_SCL
J 0
(-7335 5610);
DISPLAY 0.680851 (-7335 5610);
WIRE 16 -1 (-5175 5600)(-6175 5600);
FORCEPROP 2 LAST SIG_NAME SMB_RT_CPU0_P3_ROM_SCL
J 0
(-6060 5610);
DISPLAY 0.680851 (-6060 5610);
FORCEPROP 2 LASTPROP $XRERR UNIQUE?
J 0
(-6300 5610);
DISPLAY 0.638298 (-6300 5610);
PAINT MONO (-6300 5610);
DISPLAY INVISIBLE (-6300 5610);
WIRE 16 -1 (-5275 6425)(-5275 6350);
WIRE 16 -1 (-5575 6350)(-5275 6350);
WIRE 16 -1 (-5275 6350)(-5275 5700);
WIRE 16 -1 (-5275 5700)(-5175 5700);
WIRE 16 -1 (-5575 6225)(-5575 6350);
WIRE 16 -1 (-4525 5600)(-4175 5600);
FORCEPROP 2 LAST SIG_NAME U17_E2
J 0
(-4410 5610);
DISPLAY 0.680851 (-4410 5610);
FORCEPROP 2 LASTPROP $XRERR UNIQUE?
J 0
(-4650 5610);
DISPLAY 0.638298 (-4650 5610);
PAINT MONO (-4650 5610);
DISPLAY INVISIBLE (-4650 5610);
WIRE 16 -1 (-4175 5600)(-4175 5500);
DOT 1 (-5275 6350);
FORCENOTE
RETIMER EEPRO ADDRESS: 0XA0 (8 BIT) / 0X50 (7 BIT)
(-8300 5100) 0;
DISPLAY LEFT (-8300 5100);
DISPLAY 1.595745 (-8300 5100);
QUIT
